G04 ================== begin FILE IDENTIFICATION RECORD ==================*
G04 Layout Name:  12004-1.brd*
G04 Film Name:    BMASK*
G04 File Format:  Gerber RS274X*
G04 File Origin:  Cadence Allegro 16.2-S033*
G04 Origin Date:  Tue Oct 16 14:35:45 2012*
G04 *
G04 Layer:  VIA CLASS/SOLDERMASK_BOTTOM*
G04 Layer:  PIN/SOLDERMASK_BOTTOM*
G04 Layer:  PACKAGE GEOMETRY/SOLDERMASK_BOTTOM*
G04 Layer:  DRAWING FORMAT/LAYER_PCB_STORY*
G04 Layer:  DRAWING FORMAT/LAYER_SOLDER_B*
G04 Layer:  BOARD GEOMETRY/SOLDERMASK_BOTTOM*
G04 *
G04 Offset:    (0.00 0.00)*
G04 Mirror:    No*
G04 Mode:      Positive*
G04 Rotation:  0*
G04 FullContactRelief:  No*
G04 UndefLineWidth:     6.00*
G04 ================== end FILE IDENTIFICATION RECORD ====================*
%FSLAX35Y35*MOIN*%
%IR0*IPPOS*OFA0.00000B0.00000*MIA0B0*SFA1.00000B1.00000*%
%AMMACRO21*
4,1,40,.011,.007,
.011,-.007,
.010939,-.007695,
.010759,-.008368,
.010464,-.009,
.010064,-.009571,
.009571,-.010064,
.009,-.010464,
.008368,-.010759,
.007695,-.010939,
.007,-.011,
-.007,-.011,
-.007695,-.010939,
-.008368,-.010759,
-.009,-.010464,
-.009571,-.010064,
-.010064,-.009571,
-.010464,-.009,
-.010759,-.008368,
-.010939,-.007695,
-.011,-.007,
-.011,.007,
-.010939,.007695,
-.010759,.008368,
-.010464,.009,
-.010064,.009571,
-.009571,.010064,
-.009,.010464,
-.008368,.010759,
-.007695,.010939,
-.007,.011,
.007,.011,
.007695,.010939,
.008368,.010759,
.009,.010464,
.009571,.010064,
.010064,.009571,
.010464,.009,
.010759,.008368,
.010939,.007695,
.011,.007,
0.0*
%
%ADD21MACRO21*%
%AMMACRO44*
4,1,40,-.017,-.013,
-.017,.013,
-.016939,.013695,
-.016759,.014368,
-.016464,.015,
-.016064,.015571,
-.015571,.016064,
-.015,.016464,
-.014368,.016759,
-.013695,.016939,
-.013,.017,
.013,.017,
.013695,.016939,
.014368,.016759,
.015,.016464,
.015571,.016064,
.016064,.015571,
.016464,.015,
.016759,.014368,
.016939,.013695,
.017,.013,
.017,-.013,
.016939,-.013695,
.016759,-.014368,
.016464,-.015,
.016064,-.015571,
.015571,-.016064,
.015,-.016464,
.014368,-.016759,
.013695,-.016939,
.013,-.017,
-.013,-.017,
-.013695,-.016939,
-.014368,-.016759,
-.015,-.016464,
-.015571,-.016064,
-.016064,-.015571,
-.016464,-.015,
-.016759,-.014368,
-.016939,-.013695,
-.017,-.013,
0.0*
%
%ADD44MACRO44*%
%AMMACRO30*
4,1,40,.013,-.017,
-.013,-.017,
-.013695,-.016939,
-.014368,-.016759,
-.015,-.016464,
-.015571,-.016064,
-.016064,-.015571,
-.016464,-.015,
-.016759,-.014368,
-.016939,-.013695,
-.017,-.013,
-.017,.013,
-.016939,.013695,
-.016759,.014368,
-.016464,.015,
-.016064,.015571,
-.015571,.016064,
-.015,.016464,
-.014368,.016759,
-.013695,.016939,
-.013,.017,
.013,.017,
.013695,.016939,
.014368,.016759,
.015,.016464,
.015571,.016064,
.016064,.015571,
.016464,.015,
.016759,.014368,
.016939,.013695,
.017,.013,
.017,-.013,
.016939,-.013695,
.016759,-.014368,
.016464,-.015,
.016064,-.015571,
.015571,-.016064,
.015,-.016464,
.014368,-.016759,
.013695,-.016939,
.013,-.017,
0.0*
%
%ADD30MACRO30*%
%ADD64R,.126X.028*%
%ADD35C,.032*%
%ADD15C,.05*%
%ADD55C,.061*%
%ADD52C,.016*%
%ADD65R,.165X.028*%
%ADD48C,.062*%
%ADD38C,.055*%
%ADD22C,.028*%
%ADD14C,.046*%
%ADD63R,.081X.297*%
%ADD13C,.079*%
%AMMACRO33*
4,1,40,.007,-.011,
-.007,-.011,
-.007695,-.010939,
-.008368,-.010759,
-.009,-.010464,
-.009571,-.010064,
-.010064,-.009571,
-.010464,-.009,
-.010759,-.008368,
-.010939,-.007695,
-.011,-.007,
-.011,.007,
-.010939,.007695,
-.010759,.008368,
-.010464,.009,
-.010064,.009571,
-.009571,.010064,
-.009,.010464,
-.008368,.010759,
-.007695,.010939,
-.007,.011,
.007,.011,
.007695,.010939,
.008368,.010759,
.009,.010464,
.009571,.010064,
.010064,.009571,
.010464,.009,
.010759,.008368,
.010939,.007695,
.011,.007,
.011,-.007,
.010939,-.007695,
.010759,-.008368,
.010464,-.009,
.010064,-.009571,
.009571,-.010064,
.009,-.010464,
.008368,-.010759,
.007695,-.010939,
.007,-.011,
0.0*
%
%ADD33MACRO33*%
%AMMACRO23*
4,1,40,-.011,-.007,
-.011,.007,
-.010939,.007695,
-.010759,.008368,
-.010464,.009,
-.010064,.009571,
-.009571,.010064,
-.009,.010464,
-.008368,.010759,
-.007695,.010939,
-.007,.011,
.007,.011,
.007695,.010939,
.008368,.010759,
.009,.010464,
.009571,.010064,
.010064,.009571,
.010464,.009,
.010759,.008368,
.010939,.007695,
.011,.007,
.011,-.007,
.010939,-.007695,
.010759,-.008368,
.010464,-.009,
.010064,-.009571,
.009571,-.010064,
.009,-.010464,
.008368,-.010759,
.007695,-.010939,
.007,-.011,
-.007,-.011,
-.007695,-.010939,
-.008368,-.010759,
-.009,-.010464,
-.009571,-.010064,
-.010064,-.009571,
-.010464,-.009,
-.010759,-.008368,
-.010939,-.007695,
-.011,-.007,
0.0*
%
%ADD23MACRO23*%
%AMMACRO50*
4,1,40,-.012,-.008,
-.012,.008,
-.011939,.008695,
-.011759,.009368,
-.011464,.01,
-.011064,.010571,
-.010571,.011064,
-.01,.011464,
-.009368,.011759,
-.008695,.011939,
-.008,.012,
.008,.012,
.008695,.011939,
.009368,.011759,
.01,.011464,
.010571,.011064,
.011064,.010571,
.011464,.01,
.011759,.009368,
.011939,.008695,
.012,.008,
.012,-.008,
.011939,-.008695,
.011759,-.009368,
.011464,-.01,
.011064,-.010571,
.010571,-.011064,
.01,-.011464,
.009368,-.011759,
.008695,-.011939,
.008,-.012,
-.008,-.012,
-.008695,-.011939,
-.009368,-.011759,
-.01,-.011464,
-.010571,-.011064,
-.011064,-.010571,
-.011464,-.01,
-.011759,-.009368,
-.011939,-.008695,
-.012,-.008,
0.0*
%
%ADD50MACRO50*%
%AMMACRO32*
4,1,40,-.008,.012,
.008,.012,
.008695,.011939,
.009368,.011759,
.01,.011464,
.010571,.011064,
.011064,.010571,
.011464,.01,
.011759,.009368,
.011939,.008695,
.012,.008,
.012,-.008,
.011939,-.008695,
.011759,-.009368,
.011464,-.01,
.011064,-.010571,
.010571,-.011064,
.01,-.011464,
.009368,-.011759,
.008695,-.011939,
.008,-.012,
-.008,-.012,
-.008695,-.011939,
-.009368,-.011759,
-.01,-.011464,
-.010571,-.011064,
-.011064,-.010571,
-.011464,-.01,
-.011759,-.009368,
-.011939,-.008695,
-.012,-.008,
-.012,.008,
-.011939,.008695,
-.011759,.009368,
-.011464,.01,
-.011064,.010571,
-.010571,.011064,
-.01,.011464,
-.009368,.011759,
-.008695,.011939,
-.008,.012,
0.0*
%
%ADD32MACRO32*%
%AMMACRO45*
4,1,40,-.013,.017,
.013,.017,
.013695,.016939,
.014368,.016759,
.015,.016464,
.015571,.016064,
.016064,.015571,
.016464,.015,
.016759,.014368,
.016939,.013695,
.017,.013,
.017,-.013,
.016939,-.013695,
.016759,-.014368,
.016464,-.015,
.016064,-.015571,
.015571,-.016064,
.015,-.016464,
.014368,-.016759,
.013695,-.016939,
.013,-.017,
-.013,-.017,
-.013695,-.016939,
-.014368,-.016759,
-.015,-.016464,
-.015571,-.016064,
-.016064,-.015571,
-.016464,-.015,
-.016759,-.014368,
-.016939,-.013695,
-.017,-.013,
-.017,.013,
-.016939,.013695,
-.016759,.014368,
-.016464,.015,
-.016064,.015571,
-.015571,.016064,
-.015,.016464,
-.014368,.016759,
-.013695,.016939,
-.013,.017,
0.0*
%
%ADD45MACRO45*%
%AMMACRO53*
4,1,40,.017,.013,
.017,-.013,
.016939,-.013695,
.016759,-.014368,
.016464,-.015,
.016064,-.015571,
.015571,-.016064,
.015,-.016464,
.014368,-.016759,
.013695,-.016939,
.013,-.017,
-.013,-.017,
-.013695,-.016939,
-.014368,-.016759,
-.015,-.016464,
-.015571,-.016064,
-.016064,-.015571,
-.016464,-.015,
-.016759,-.014368,
-.016939,-.013695,
-.017,-.013,
-.017,.013,
-.016939,.013695,
-.016759,.014368,
-.016464,.015,
-.016064,.015571,
-.015571,.016064,
-.015,.016464,
-.014368,.016759,
-.013695,.016939,
-.013,.017,
.013,.017,
.013695,.016939,
.014368,.016759,
.015,.016464,
.015571,.016064,
.016064,.015571,
.016464,.015,
.016759,.014368,
.016939,.013695,
.017,.013,
0.0*
%
%ADD53MACRO53*%
%AMMACRO34*
4,1,40,.007,-.011,
-.007,-.011,
-.007695,-.010939,
-.008368,-.010759,
-.009,-.010464,
-.009571,-.010064,
-.010064,-.009571,
-.010464,-.009,
-.010759,-.008368,
-.010939,-.007695,
-.011,-.007,
-.011,.007,
-.010939,.007695,
-.010759,.008368,
-.010464,.009,
-.010064,.009571,
-.009571,.010064,
-.009,.010464,
-.008368,.010759,
-.007695,.010939,
-.007,.011,
.007,.011,
.007695,.010939,
.008368,.010759,
.009,.010464,
.009571,.010064,
.010064,.009571,
.010464,.009,
.010759,.008368,
.010939,.007695,
.011,.007,
.011,-.007,
.010939,-.007695,
.010759,-.008368,
.010464,-.009,
.010064,-.009571,
.009571,-.010064,
.009,-.010464,
.008368,-.010759,
.007695,-.010939,
.007,-.011,
0.0*
%
%ADD34MACRO34*%
%AMMACRO24*
4,1,40,-.011,-.007,
-.011,.007,
-.010939,.007695,
-.010759,.008368,
-.010464,.009,
-.010064,.009571,
-.009571,.010064,
-.009,.010464,
-.008368,.010759,
-.007695,.010939,
-.007,.011,
.007,.011,
.007695,.010939,
.008368,.010759,
.009,.010464,
.009571,.010064,
.010064,.009571,
.010464,.009,
.010759,.008368,
.010939,.007695,
.011,.007,
.011,-.007,
.010939,-.007695,
.010759,-.008368,
.010464,-.009,
.010064,-.009571,
.009571,-.010064,
.009,-.010464,
.008368,-.010759,
.007695,-.010939,
.007,-.011,
-.007,-.011,
-.007695,-.010939,
-.008368,-.010759,
-.009,-.010464,
-.009571,-.010064,
-.010064,-.009571,
-.010464,-.009,
-.010759,-.008368,
-.010939,-.007695,
-.011,-.007,
0.0*
%
%ADD24MACRO24*%
%AMMACRO49*
4,1,40,-.012,-.008,
-.012,.008,
-.011939,.008695,
-.011759,.009368,
-.011464,.01,
-.011064,.010571,
-.010571,.011064,
-.01,.011464,
-.009368,.011759,
-.008695,.011939,
-.008,.012,
.008,.012,
.008695,.011939,
.009368,.011759,
.01,.011464,
.010571,.011064,
.011064,.010571,
.011464,.01,
.011759,.009368,
.011939,.008695,
.012,.008,
.012,-.008,
.011939,-.008695,
.011759,-.009368,
.011464,-.01,
.011064,-.010571,
.010571,-.011064,
.01,-.011464,
.009368,-.011759,
.008695,-.011939,
.008,-.012,
-.008,-.012,
-.008695,-.011939,
-.009368,-.011759,
-.01,-.011464,
-.010571,-.011064,
-.011064,-.010571,
-.011464,-.01,
-.011759,-.009368,
-.011939,-.008695,
-.012,-.008,
0.0*
%
%ADD49MACRO49*%
%AMMACRO31*
4,1,40,-.008,.012,
.008,.012,
.008695,.011939,
.009368,.011759,
.01,.011464,
.010571,.011064,
.011064,.010571,
.011464,.01,
.011759,.009368,
.011939,.008695,
.012,.008,
.012,-.008,
.011939,-.008695,
.011759,-.009368,
.011464,-.01,
.011064,-.010571,
.010571,-.011064,
.01,-.011464,
.009368,-.011759,
.008695,-.011939,
.008,-.012,
-.008,-.012,
-.008695,-.011939,
-.009368,-.011759,
-.01,-.011464,
-.010571,-.011064,
-.011064,-.010571,
-.011464,-.01,
-.011759,-.009368,
-.011939,-.008695,
-.012,-.008,
-.012,.008,
-.011939,.008695,
-.011759,.009368,
-.011464,.01,
-.011064,.010571,
-.010571,.011064,
-.01,.011464,
-.009368,.011759,
-.008695,.011939,
-.008,.012,
0.0*
%
%ADD31MACRO31*%
%AMMACRO46*
4,1,40,-.013,.017,
.013,.017,
.013695,.016939,
.014368,.016759,
.015,.016464,
.015571,.016064,
.016064,.015571,
.016464,.015,
.016759,.014368,
.016939,.013695,
.017,.013,
.017,-.013,
.016939,-.013695,
.016759,-.014368,
.016464,-.015,
.016064,-.015571,
.015571,-.016064,
.015,-.016464,
.014368,-.016759,
.013695,-.016939,
.013,-.017,
-.013,-.017,
-.013695,-.016939,
-.014368,-.016759,
-.015,-.016464,
-.015571,-.016064,
-.016064,-.015571,
-.016464,-.015,
-.016759,-.014368,
-.016939,-.013695,
-.017,-.013,
-.017,.013,
-.016939,.013695,
-.016759,.014368,
-.016464,.015,
-.016064,.015571,
-.015571,.016064,
-.015,.016464,
-.014368,.016759,
-.013695,.016939,
-.013,.017,
0.0*
%
%ADD46MACRO46*%
%AMMACRO54*
4,1,40,.017,.013,
.017,-.013,
.016939,-.013695,
.016759,-.014368,
.016464,-.015,
.016064,-.015571,
.015571,-.016064,
.015,-.016464,
.014368,-.016759,
.013695,-.016939,
.013,-.017,
-.013,-.017,
-.013695,-.016939,
-.014368,-.016759,
-.015,-.016464,
-.015571,-.016064,
-.016064,-.015571,
-.016464,-.015,
-.016759,-.014368,
-.016939,-.013695,
-.017,-.013,
-.017,.013,
-.016939,.013695,
-.016759,.014368,
-.016464,.015,
-.016064,.015571,
-.015571,.016064,
-.015,.016464,
-.014368,.016759,
-.013695,.016939,
-.013,.017,
.013,.017,
.013695,.016939,
.014368,.016759,
.015,.016464,
.015571,.016064,
.016064,.015571,
.016464,.015,
.016759,.014368,
.016939,.013695,
.017,.013,
0.0*
%
%ADD54MACRO54*%
%ADD59R,.042X.014*%
%ADD58R,.014X.042*%
%ADD47R,.045X.03*%
%ADD28R,.03X.045*%
%ADD62R,.038X.012*%
%ADD61R,.012X.038*%
%ADD39R,.016X.06*%
%ADD10C,.14*%
%ADD16C,.213*%
%ADD27R,.065X.05*%
%ADD56R,.045X.055*%
%ADD51R,.014X.076*%
%ADD37R,.12X.12*%
%ADD36R,.076X.014*%
%ADD40R,.055X.045*%
%ADD12C,.158*%
%ADD11R,.16X.16*%
%ADD60C,.197*%
%ADD57R,.128X.128*%
%AMMACRO17*
4,1,40,-.02,-.006,
-.019878,-.007389,
-.019518,-.008736,
-.018928,-.01,
-.018128,-.011142,
-.017142,-.012128,
-.016,-.012928,
-.014736,-.013518,
-.013389,-.013878,
-.012,-.014,
.012,-.014,
.013389,-.013878,
.014736,-.013518,
.016,-.012928,
.017142,-.012128,
.018128,-.011142,
.018928,-.01,
.019518,-.008736,
.019878,-.007389,
.02,-.006,
.02,.006,
.019878,.007389,
.019518,.008736,
.018928,.01,
.018128,.011142,
.017142,.012128,
.016,.012928,
.014736,.013518,
.013389,.013878,
.012,.014,
-.012,.014,
-.013389,.013878,
-.014736,.013518,
-.016,.012928,
-.017142,.012128,
-.018128,.011142,
-.018928,.01,
-.019518,.008736,
-.019878,.007389,
-.02,.006,
-.02,-.006,
0.0*
%
%ADD17MACRO17*%
%AMMACRO42*
4,1,40,.012,.008,
.012,-.008,
.011939,-.008695,
.011759,-.009368,
.011464,-.01,
.011064,-.010571,
.010571,-.011064,
.01,-.011464,
.009368,-.011759,
.008695,-.011939,
.008,-.012,
-.008,-.012,
-.008695,-.011939,
-.009368,-.011759,
-.01,-.011464,
-.010571,-.011064,
-.011064,-.010571,
-.011464,-.01,
-.011759,-.009368,
-.011939,-.008695,
-.012,-.008,
-.012,.008,
-.011939,.008695,
-.011759,.009368,
-.011464,.01,
-.011064,.010571,
-.010571,.011064,
-.01,.011464,
-.009368,.011759,
-.008695,.011939,
-.008,.012,
.008,.012,
.008695,.011939,
.009368,.011759,
.01,.011464,
.010571,.011064,
.011064,.010571,
.011464,.01,
.011759,.009368,
.011939,.008695,
.012,.008,
0.0*
%
%ADD42MACRO42*%
%AMMACRO26*
4,1,40,-.007,.011,
.007,.011,
.007695,.010939,
.008368,.010759,
.009,.010464,
.009571,.010064,
.010064,.009571,
.010464,.009,
.010759,.008368,
.010939,.007695,
.011,.007,
.011,-.007,
.010939,-.007695,
.010759,-.008368,
.010464,-.009,
.010064,-.009571,
.009571,-.010064,
.009,-.010464,
.008368,-.010759,
.007695,-.010939,
.007,-.011,
-.007,-.011,
-.007695,-.010939,
-.008368,-.010759,
-.009,-.010464,
-.009571,-.010064,
-.010064,-.009571,
-.010464,-.009,
-.010759,-.008368,
-.010939,-.007695,
-.011,-.007,
-.011,.007,
-.010939,.007695,
-.010759,.008368,
-.010464,.009,
-.010064,.009571,
-.009571,.010064,
-.009,.010464,
-.008368,.010759,
-.007695,.010939,
-.007,.011,
0.0*
%
%ADD26MACRO26*%
%AMMACRO19*
4,1,40,.008,-.012,
-.008,-.012,
-.008695,-.011939,
-.009368,-.011759,
-.01,-.011464,
-.010571,-.011064,
-.011064,-.010571,
-.011464,-.01,
-.011759,-.009368,
-.011939,-.008695,
-.012,-.008,
-.012,.008,
-.011939,.008695,
-.011759,.009368,
-.011464,.01,
-.011064,.010571,
-.010571,.011064,
-.01,.011464,
-.009368,.011759,
-.008695,.011939,
-.008,.012,
.008,.012,
.008695,.011939,
.009368,.011759,
.01,.011464,
.010571,.011064,
.011064,.010571,
.011464,.01,
.011759,.009368,
.011939,.008695,
.012,.008,
.012,-.008,
.011939,-.008695,
.011759,-.009368,
.011464,-.01,
.011064,-.010571,
.010571,-.011064,
.01,-.011464,
.009368,-.011759,
.008695,-.011939,
.008,-.012,
0.0*
%
%ADD19MACRO19*%
%AMMACRO20*
4,1,40,.011,.007,
.011,-.007,
.010939,-.007695,
.010759,-.008368,
.010464,-.009,
.010064,-.009571,
.009571,-.010064,
.009,-.010464,
.008368,-.010759,
.007695,-.010939,
.007,-.011,
-.007,-.011,
-.007695,-.010939,
-.008368,-.010759,
-.009,-.010464,
-.009571,-.010064,
-.010064,-.009571,
-.010464,-.009,
-.010759,-.008368,
-.010939,-.007695,
-.011,-.007,
-.011,.007,
-.010939,.007695,
-.010759,.008368,
-.010464,.009,
-.010064,.009571,
-.009571,.010064,
-.009,.010464,
-.008368,.010759,
-.007695,.010939,
-.007,.011,
.007,.011,
.007695,.010939,
.008368,.010759,
.009,.010464,
.009571,.010064,
.010064,.009571,
.010464,.009,
.010759,.008368,
.010939,.007695,
.011,.007,
0.0*
%
%ADD20MACRO20*%
%AMMACRO43*
4,1,40,-.017,-.013,
-.017,.013,
-.016939,.013695,
-.016759,.014368,
-.016464,.015,
-.016064,.015571,
-.015571,.016064,
-.015,.016464,
-.014368,.016759,
-.013695,.016939,
-.013,.017,
.013,.017,
.013695,.016939,
.014368,.016759,
.015,.016464,
.015571,.016064,
.016064,.015571,
.016464,.015,
.016759,.014368,
.016939,.013695,
.017,.013,
.017,-.013,
.016939,-.013695,
.016759,-.014368,
.016464,-.015,
.016064,-.015571,
.015571,-.016064,
.015,-.016464,
.014368,-.016759,
.013695,-.016939,
.013,-.017,
-.013,-.017,
-.013695,-.016939,
-.014368,-.016759,
-.015,-.016464,
-.015571,-.016064,
-.016064,-.015571,
-.016464,-.015,
-.016759,-.014368,
-.016939,-.013695,
-.017,-.013,
0.0*
%
%ADD43MACRO43*%
%AMMACRO29*
4,1,40,.013,-.017,
-.013,-.017,
-.013695,-.016939,
-.014368,-.016759,
-.015,-.016464,
-.015571,-.016064,
-.016064,-.015571,
-.016464,-.015,
-.016759,-.014368,
-.016939,-.013695,
-.017,-.013,
-.017,.013,
-.016939,.013695,
-.016759,.014368,
-.016464,.015,
-.016064,.015571,
-.015571,.016064,
-.015,.016464,
-.014368,.016759,
-.013695,.016939,
-.013,.017,
.013,.017,
.013695,.016939,
.014368,.016759,
.015,.016464,
.015571,.016064,
.016064,.015571,
.016464,.015,
.016759,.014368,
.016939,.013695,
.017,.013,
.017,-.013,
.016939,-.013695,
.016759,-.014368,
.016464,-.015,
.016064,-.015571,
.015571,-.016064,
.015,-.016464,
.014368,-.016759,
.013695,-.016939,
.013,-.017,
0.0*
%
%ADD29MACRO29*%
%AMMACRO41*
4,1,40,.012,.008,
.012,-.008,
.011939,-.008695,
.011759,-.009368,
.011464,-.01,
.011064,-.010571,
.010571,-.011064,
.01,-.011464,
.009368,-.011759,
.008695,-.011939,
.008,-.012,
-.008,-.012,
-.008695,-.011939,
-.009368,-.011759,
-.01,-.011464,
-.010571,-.011064,
-.011064,-.010571,
-.011464,-.01,
-.011759,-.009368,
-.011939,-.008695,
-.012,-.008,
-.012,.008,
-.011939,.008695,
-.011759,.009368,
-.011464,.01,
-.011064,.010571,
-.010571,.011064,
-.01,.011464,
-.009368,.011759,
-.008695,.011939,
-.008,.012,
.008,.012,
.008695,.011939,
.009368,.011759,
.01,.011464,
.010571,.011064,
.011064,.010571,
.011464,.01,
.011759,.009368,
.011939,.008695,
.012,.008,
0.0*
%
%ADD41MACRO41*%
%AMMACRO25*
4,1,40,-.007,.011,
.007,.011,
.007695,.010939,
.008368,.010759,
.009,.010464,
.009571,.010064,
.010064,.009571,
.010464,.009,
.010759,.008368,
.010939,.007695,
.011,.007,
.011,-.007,
.010939,-.007695,
.010759,-.008368,
.010464,-.009,
.010064,-.009571,
.009571,-.010064,
.009,-.010464,
.008368,-.010759,
.007695,-.010939,
.007,-.011,
-.007,-.011,
-.007695,-.010939,
-.008368,-.010759,
-.009,-.010464,
-.009571,-.010064,
-.010064,-.009571,
-.010464,-.009,
-.010759,-.008368,
-.010939,-.007695,
-.011,-.007,
-.011,.007,
-.010939,.007695,
-.010759,.008368,
-.010464,.009,
-.010064,.009571,
-.009571,.010064,
-.009,.010464,
-.008368,.010759,
-.007695,.010939,
-.007,.011,
0.0*
%
%ADD25MACRO25*%
%AMMACRO18*
4,1,40,.008,-.012,
-.008,-.012,
-.008695,-.011939,
-.009368,-.011759,
-.01,-.011464,
-.010571,-.011064,
-.011064,-.010571,
-.011464,-.01,
-.011759,-.009368,
-.011939,-.008695,
-.012,-.008,
-.012,.008,
-.011939,.008695,
-.011759,.009368,
-.011464,.01,
-.011064,.010571,
-.010571,.011064,
-.01,.011464,
-.009368,.011759,
-.008695,.011939,
-.008,.012,
.008,.012,
.008695,.011939,
.009368,.011759,
.01,.011464,
.010571,.011064,
.011064,.010571,
.011464,.01,
.011759,.009368,
.011939,.008695,
.012,.008,
.012,-.008,
.011939,-.008695,
.011759,-.009368,
.011464,-.01,
.011064,-.010571,
.010571,-.011064,
.01,-.011464,
.009368,-.011759,
.008695,-.011939,
.008,-.012,
0.0*
%
%ADD18MACRO18*%
%ADD66C,.02*%
%ADD67C,.006*%
G75*
%LPD*%
G75*
G36*
G01X795276Y328170D02*
Y660060D01*
X773264D01*
Y328170D01*
X795276D01*
G37*
G36*
G01Y737619D02*
Y817541D01*
X773264D01*
Y737619D01*
X795276D01*
G37*
G54D10*
X-1011811Y-15748D03*
Y940945D03*
X775591Y-15748D03*
Y940944D03*
G54D20*
X74800Y87800D03*
X43851Y178828D03*
X43794Y193758D03*
X22900Y310200D03*
X39236Y280487D03*
X27000Y310100D03*
X31100D03*
X63942Y534279D03*
X67065Y515737D03*
X98138Y402278D03*
X89163Y386883D03*
X94076Y411254D03*
X118163Y470983D03*
X149799Y448926D03*
X428616Y433629D03*
X684869Y434811D03*
X680738Y434833D03*
X693509Y434901D03*
X689111Y434812D03*
X705600Y551200D03*
X663300Y526200D03*
X648200Y552100D03*
X705927Y528727D03*
X668699Y552630D03*
X726040Y547196D03*
G54D11*
X-944882Y-17185D03*
Y942382D03*
X708683Y-17218D03*
G54D12*
X-59094Y277559D03*
X-7913D03*
X109410Y796831D03*
Y876397D03*
X168465Y796831D03*
Y876397D03*
G54D30*
X53540Y212898D03*
G54D21*
X74800Y91200D03*
X43851Y182228D03*
X43794Y197158D03*
X22900Y313600D03*
X39236Y283887D03*
X27000Y313500D03*
X31100D03*
X63942Y537679D03*
X67065Y519137D03*
X98138Y405678D03*
X89163Y390283D03*
X94076Y414654D03*
X118163Y474383D03*
X149799Y452326D03*
X428616Y437029D03*
X684869Y438211D03*
X680738Y438233D03*
X693509Y438301D03*
X689111Y438212D03*
X705600Y554600D03*
X663300Y529600D03*
X648200Y555500D03*
X705927Y532127D03*
X668699Y556030D03*
X726040Y550596D03*
G54D40*
X75876Y307064D03*
Y314664D03*
X50799Y499966D03*
Y492366D03*
X400934Y446386D03*
Y453986D03*
X393110Y446429D03*
Y454029D03*
G54D31*
X63444Y266211D03*
X38892Y293747D03*
X130163Y413483D03*
X137163Y434483D03*
X129768Y422719D03*
X434994Y457361D03*
X435016Y449543D03*
G54D13*
X-33503Y269685D03*
G54D22*
X76800Y99900D03*
X63700Y194818D03*
X71100Y181200D03*
X69100Y195200D03*
X47100Y267600D03*
X67800Y250100D03*
X67039Y272085D03*
X70415Y260333D03*
X70188Y224633D03*
X40500Y227100D03*
X14200Y339400D03*
X45215Y283633D03*
X25700Y306400D03*
X70118Y287233D03*
X30700Y306300D03*
X70015Y294733D03*
X70238Y279733D03*
X33722Y394233D03*
X18115Y413228D03*
X20915Y348544D03*
X39244Y411695D03*
X46741Y411938D03*
X27715Y410133D03*
X22646Y397233D03*
X16415Y361841D03*
X73100Y380933D03*
X59215Y375233D03*
X18915Y449033D03*
X34334Y438445D03*
X22315Y441743D03*
X38115Y445328D03*
X31134Y449532D03*
X51425Y453027D03*
X64700Y506200D03*
X75702Y536228D03*
X69200Y531100D03*
X70115Y541233D03*
X70900Y519700D03*
X39353Y708533D03*
X92600Y79800D03*
X146015Y79433D03*
X83800Y188800D03*
X111482Y202800D03*
X113815Y194333D03*
X122400Y199000D03*
X98968Y194794D03*
X115115Y166600D03*
X89300Y144600D03*
X125600Y228985D03*
X87200Y222000D03*
X98715Y313833D03*
X87115Y331571D03*
X119615Y312033D03*
X84958Y305933D03*
X100315Y305033D03*
X141315Y305433D03*
X97000Y389200D03*
X90815Y445833D03*
X90501Y480516D03*
X98286Y465448D03*
X125853Y473129D03*
X89400Y659100D03*
X80200Y633900D03*
X83500Y653600D03*
Y640044D03*
X84900Y747900D03*
X85300Y755100D03*
X85000Y775900D03*
X84100Y769000D03*
X197900Y82000D03*
X216415Y108238D03*
X208115Y95933D03*
X186615Y83733D03*
X201614Y89932D03*
X152400Y124300D03*
X170302Y147100D03*
X158100Y166800D03*
X167015Y167633D03*
X163550Y179657D03*
X151615Y176111D03*
X188590Y262541D03*
X176915Y255433D03*
X188115Y253008D03*
X169800Y274100D03*
X169715Y250448D03*
X168115Y308933D03*
X187615Y289433D03*
X170800Y297900D03*
X191615Y282933D03*
X177215Y279133D03*
X156515Y305233D03*
X170315Y284833D03*
X170596Y292689D03*
X219728Y457397D03*
X197885Y436402D03*
X181400Y485900D03*
X205881Y441150D03*
X199315Y447233D03*
X206917Y435857D03*
X212300Y439300D03*
X209000Y447500D03*
X205400Y462100D03*
X241817Y72536D03*
X242488Y88466D03*
X279629Y405032D03*
X257015Y394833D03*
X249300Y398800D03*
X251100Y408500D03*
X244600Y485200D03*
X290615Y432406D03*
X267673Y429991D03*
X237576Y417080D03*
X253615Y428333D03*
X245000Y432000D03*
X258100Y452100D03*
X241565Y437435D03*
X253500Y458500D03*
X241300Y449000D03*
X221800Y436500D03*
X237980Y467226D03*
X240400Y423600D03*
X224015Y427633D03*
X267479Y420536D03*
X226000Y447700D03*
X233900Y455700D03*
X223500Y469900D03*
X228800Y481300D03*
X224700Y462200D03*
X243300Y464500D03*
X226818Y439263D03*
X291453Y414238D03*
X299330Y417148D03*
X356380Y476847D03*
X426700Y475000D03*
X423746Y470900D03*
X414894Y453432D03*
X419296Y449111D03*
X423572Y453454D03*
X419092Y457572D03*
X419225Y453324D03*
X410015Y479733D03*
X400515Y433533D03*
X440715Y444133D03*
X440815Y458633D03*
X434515Y436133D03*
X493050Y486350D03*
X444115Y490049D03*
X498794Y493300D03*
X500894Y499600D03*
X489000Y493700D03*
X503300Y539700D03*
X634700Y544300D03*
X640900Y546800D03*
X639200Y540600D03*
X639900Y554500D03*
X626700Y586700D03*
X688409Y442578D03*
X693409Y442656D03*
X703400Y442200D03*
X698404Y442423D03*
X694995Y453626D03*
X694923Y461253D03*
X694851Y469456D03*
X694907Y476993D03*
X675415Y437533D03*
X683409Y442604D03*
X708300Y480600D03*
X707900Y485800D03*
X689200Y511600D03*
X673100Y535400D03*
X711500Y490200D03*
X680800Y542100D03*
X685800Y549900D03*
X677815Y493833D03*
X706695Y559800D03*
X680700Y558000D03*
X688600Y557800D03*
X649500Y564300D03*
X680300Y584400D03*
X704215Y762804D03*
X712215Y766571D03*
X684515Y760867D03*
X703515Y771013D03*
X711815Y775149D03*
X703415Y779285D03*
X704215Y787599D03*
Y799456D03*
X704015Y834000D03*
X680706Y781109D03*
X687848Y783400D03*
X686672Y793470D03*
X685389Y802213D03*
X705215Y824663D03*
X703515Y842302D03*
X711415Y846395D03*
X703415Y850609D03*
X754457Y530156D03*
X747015Y518472D03*
X759115Y524233D03*
X761015Y536033D03*
X739385Y553915D03*
X728300Y531200D03*
X756433Y503965D03*
X754615Y511733D03*
X746300Y504900D03*
X761355Y516454D03*
X761900Y508300D03*
X756900Y554700D03*
X761000Y551800D03*
X742400Y559900D03*
X736176Y583406D03*
X761400Y560500D03*
X756900Y563300D03*
X748900Y644700D03*
X755115Y740179D03*
X744615Y759864D03*
X713015Y783400D03*
X715515Y791967D03*
X713915Y802017D03*
X713715Y829925D03*
X713015Y838158D03*
X744700Y828200D03*
X742336Y838933D03*
X731615Y846447D03*
X726013Y855385D03*
X716539Y852514D03*
G54D41*
X60983Y392640D03*
Y389240D03*
X63585Y496598D03*
X120763Y228683D03*
X110063Y228783D03*
X109736Y306270D03*
X91863Y382983D03*
X106257Y409989D03*
X91752Y379460D03*
X95400Y455100D03*
X110863Y430483D03*
X115063Y448583D03*
X118880Y465509D03*
X132163Y441583D03*
X118813Y461961D03*
X118794Y458462D03*
X150563Y228783D03*
X150763Y305503D03*
X172478Y473409D03*
X171943Y469870D03*
X149899Y461877D03*
X679465Y467377D03*
Y463877D03*
X681909Y453623D03*
X679684Y546217D03*
X714291Y564572D03*
G54D32*
X63444Y262611D03*
X38892Y290147D03*
X130163Y409883D03*
X137163Y430883D03*
X129768Y419119D03*
X434994Y453761D03*
X435016Y445943D03*
G54D50*
X65600Y609872D03*
Y605972D03*
X65700Y600272D03*
Y596372D03*
Y576887D03*
Y572987D03*
X65800Y567387D03*
Y563487D03*
X66251Y694403D03*
Y690503D03*
Y684703D03*
Y680803D03*
X65200Y728513D03*
Y724613D03*
X65300Y718613D03*
Y714713D03*
X134700Y228600D03*
X94363Y228783D03*
X94419Y305456D03*
X124863Y305503D03*
X135563Y305603D03*
X110405Y413570D03*
X118463Y421283D03*
X124563Y441583D03*
X125363Y449983D03*
X116963Y441583D03*
X113063Y434383D03*
X139763Y441583D03*
X133263Y449183D03*
X122863Y433683D03*
X130583Y434871D03*
Y431371D03*
X133263Y452683D03*
X175296Y269694D03*
X171869Y432425D03*
X160663Y440683D03*
X154240Y837095D03*
X154351Y832781D03*
Y828981D03*
X155836Y817740D03*
Y814140D03*
X155088Y853750D03*
X155161Y850210D03*
X154040Y840895D03*
X711530Y464221D03*
X711609Y453723D03*
X657300Y533400D03*
G54D23*
X43848Y189691D03*
X30773Y274407D03*
X35107Y274462D03*
X67367Y526739D03*
X63918Y545213D03*
X113749Y313569D03*
X93263Y390283D03*
X107363Y450183D03*
X94500Y465600D03*
X91167Y491594D03*
X181278Y247657D03*
X424282Y437118D03*
X707109Y438423D03*
X698367Y438402D03*
X702508Y438404D03*
X705600Y547000D03*
X663300Y522000D03*
X648200Y548000D03*
X705928Y524645D03*
X668705Y548544D03*
X685815Y493278D03*
X689996Y493247D03*
X698475Y493274D03*
X694196Y493347D03*
X707296D03*
X702648Y493237D03*
X668743Y541065D03*
X726045Y543153D03*
G54D14*
X6614Y553544D03*
X10551Y623622D03*
X6614Y671654D03*
X10551Y741732D03*
X18425Y553544D03*
X32204D03*
X18425Y623622D03*
X32204D03*
X18425Y671654D03*
X32204D03*
X18425Y741732D03*
X32204D03*
G54D42*
X57383Y392640D03*
Y389240D03*
X59985Y496598D03*
X146963Y228783D03*
X117163Y228683D03*
X106463Y228783D03*
X106136Y306270D03*
X147163Y305503D03*
X88263Y382983D03*
X102657Y409989D03*
X88152Y379460D03*
X91800Y455100D03*
X107263Y430483D03*
X111463Y448583D03*
X115280Y465509D03*
X128563Y441583D03*
X146299Y461877D03*
X115213Y461961D03*
X115194Y458462D03*
X168878Y473409D03*
X168343Y469870D03*
X675865Y467377D03*
Y463877D03*
X678309Y453623D03*
X676084Y546217D03*
X710691Y564572D03*
G54D60*
X716535Y39370D03*
G54D51*
X82858Y236883D03*
X85418D03*
X87973D03*
X90533D03*
X93093D03*
X95653D03*
X98213D03*
X100768D03*
X103328D03*
X105888D03*
X108448D03*
X111008D03*
X113563D03*
X116123D03*
X118683D03*
X146833D03*
X144273D03*
X141713D03*
X139158D03*
X136598D03*
X134038D03*
X131478D03*
X128918D03*
X126363D03*
X123803D03*
X121243D03*
X146833Y297283D03*
X144273D03*
X141713D03*
X139158D03*
X136598D03*
X134038D03*
X131478D03*
X128918D03*
X126363D03*
X123803D03*
X121243D03*
X82858D03*
X85418D03*
X87973D03*
X90533D03*
X93093D03*
X95653D03*
X98213D03*
X100768D03*
X103328D03*
X105888D03*
X108448D03*
X111008D03*
X113563D03*
X116123D03*
X118683D03*
X157068Y236883D03*
X154508D03*
X151953D03*
X149393D03*
X157068Y297283D03*
X154508D03*
X151953D03*
X149393D03*
G54D24*
X43848Y186291D03*
X30773Y271007D03*
X35107Y271062D03*
X67367Y523339D03*
X63918Y541813D03*
X113749Y310169D03*
X93263Y386883D03*
X107363Y446783D03*
X94500Y462200D03*
X91167Y488194D03*
X181278Y244257D03*
X424282Y433718D03*
X707109Y435023D03*
X698367Y435002D03*
X702508Y435004D03*
X705600Y543600D03*
X663300Y518600D03*
X648200Y544600D03*
X705928Y521245D03*
X668705Y545144D03*
X685815Y489878D03*
X689996Y489847D03*
X698475Y489874D03*
X694196Y489947D03*
X707296D03*
X702648Y489837D03*
X668743Y537665D03*
X726045Y539753D03*
G54D33*
X62358Y211203D03*
X57483Y385340D03*
X55073Y443238D03*
X48131Y476567D03*
X59963Y488683D03*
X51120Y530394D03*
X113763Y306003D03*
X89463Y397283D03*
X171155Y265687D03*
X171111Y261545D03*
X173700Y273900D03*
X173715Y244229D03*
X176608Y289824D03*
X233100Y482400D03*
Y486500D03*
Y478300D03*
Y474200D03*
X427649Y469469D03*
X686400Y545500D03*
X653367Y563931D03*
X693829Y766898D03*
X693807Y762804D03*
X693820Y838158D03*
X693779Y834000D03*
X693800Y829925D03*
X694630Y800492D03*
X694504Y796145D03*
X694293Y791967D03*
X693998Y787599D03*
X693955Y783400D03*
X693934Y779285D03*
X693913Y775149D03*
X693870Y771013D03*
X693947Y854741D03*
X693916Y850609D03*
X693887Y846395D03*
X693868Y842302D03*
X686310Y854661D03*
X726900Y535700D03*
X749500Y554700D03*
Y550600D03*
Y563300D03*
Y559200D03*
X738263Y855068D03*
G54D15*
X22980Y59055D03*
X30854D03*
X22980Y106299D03*
Y98425D03*
Y90551D03*
Y82677D03*
Y74803D03*
Y66929D03*
X30854Y106299D03*
Y98425D03*
Y90551D03*
Y82677D03*
Y74803D03*
Y66929D03*
X41142Y135669D03*
Y155669D03*
Y145669D03*
X26181Y537559D03*
Y527559D03*
Y517559D03*
X41142Y655669D03*
Y645669D03*
Y635669D03*
Y763780D03*
Y753780D03*
Y773780D03*
G54D25*
X76300Y144900D03*
X62368Y198735D03*
X72706Y185541D03*
X62359Y202789D03*
X60200Y251200D03*
X62347Y206909D03*
X57483Y381140D03*
X70763Y386683D03*
X55507Y450659D03*
X55550Y455007D03*
X43473Y528179D03*
X83100Y225900D03*
X84550Y409763D03*
X89463Y401383D03*
X88564Y405439D03*
X176564Y294017D03*
X416638Y471346D03*
X416632Y475470D03*
X712245Y485000D03*
Y480900D03*
X693400Y511400D03*
X710826Y560695D03*
X693856Y825792D03*
X712900Y529600D03*
Y525500D03*
X737982Y850566D03*
X737962Y846447D03*
X738100Y859500D03*
G54D43*
X43500Y540200D03*
X118263Y415283D03*
X126310Y465403D03*
X102643Y465497D03*
X680800Y534800D03*
X701500D03*
G54D16*
X29528Y19685D03*
X76772D03*
X108268Y905512D03*
X155512D03*
G54D61*
X691905Y448220D03*
X693874D03*
X695842D03*
X697811D03*
Y483820D03*
X695842D03*
X693874D03*
X691905D03*
G54D34*
X65758Y211203D03*
X60883Y385340D03*
X58473Y443238D03*
X51531Y476567D03*
X63363Y488683D03*
X54520Y530394D03*
X117163Y306003D03*
X92863Y397283D03*
X174555Y265687D03*
X174511Y261545D03*
X177100Y273900D03*
X177115Y244229D03*
X180008Y289824D03*
X236500Y482400D03*
Y486500D03*
Y478300D03*
Y474200D03*
X431049Y469469D03*
X689800Y545500D03*
X656767Y563931D03*
X697229Y766898D03*
X697207Y762804D03*
X697220Y838158D03*
X697179Y834000D03*
X697200Y829925D03*
X698030Y800492D03*
X697904Y796145D03*
X697693Y791967D03*
X697398Y787599D03*
X697355Y783400D03*
X697334Y779285D03*
X697313Y775149D03*
X697270Y771013D03*
X697347Y854741D03*
X697316Y850609D03*
X697287Y846395D03*
X697268Y842302D03*
X689710Y854661D03*
X730300Y535700D03*
X752900Y554700D03*
Y550600D03*
Y563300D03*
Y559200D03*
X741663Y855068D03*
G54D52*
X128918Y307533D03*
X702000Y485700D03*
X688615Y485133D03*
X682015Y493633D03*
G54D26*
X65768Y198735D03*
X76106Y185541D03*
X65759Y202789D03*
X63600Y251200D03*
X65747Y206909D03*
X60883Y381140D03*
X74163Y386683D03*
X58907Y450659D03*
X58950Y455007D03*
X46873Y528179D03*
X79700Y144900D03*
X86500Y225900D03*
X87950Y409763D03*
X92863Y401383D03*
X91964Y405439D03*
X179964Y294017D03*
X420038Y471346D03*
X420032Y475470D03*
X696800Y511400D03*
X697256Y825792D03*
X715645Y485000D03*
Y480900D03*
X716300Y529600D03*
Y525500D03*
X714226Y560695D03*
X741382Y850566D03*
X741362Y846447D03*
X741500Y859500D03*
G54D17*
X76107Y131131D03*
Y138611D03*
X83977Y134871D03*
G54D62*
X701858Y450272D03*
Y452240D03*
Y454209D03*
Y456177D03*
Y458146D03*
Y460114D03*
Y462083D03*
Y464051D03*
Y466020D03*
Y467989D03*
Y469957D03*
Y471926D03*
Y473894D03*
Y475863D03*
Y477831D03*
Y479800D03*
Y481768D03*
X687858D03*
Y479800D03*
Y477831D03*
Y475863D03*
Y473894D03*
Y471926D03*
Y469957D03*
Y467989D03*
Y466020D03*
Y464051D03*
Y462083D03*
Y460114D03*
Y458146D03*
Y456177D03*
Y454209D03*
Y452240D03*
Y450272D03*
G54D53*
X102363Y449283D03*
X125579Y421573D03*
X701500Y518600D03*
X680800D03*
G54D35*
X25600Y274900D03*
X18900Y306200D03*
X76251Y401844D03*
X56569Y399551D03*
X58691Y404840D03*
X66136Y371769D03*
X79502Y394485D03*
X71915Y366033D03*
X73615Y371533D03*
X48515Y482733D03*
X65382Y422433D03*
X33315Y473433D03*
X77915Y469095D03*
X64415Y446133D03*
X70613Y484810D03*
X63000Y471442D03*
X41215Y474533D03*
X33715Y481333D03*
X41262Y467436D03*
X32548Y465241D03*
X56795Y466429D03*
X57663Y473783D03*
X46007Y446236D03*
X34821Y456887D03*
X50845Y466404D03*
X53815Y485033D03*
X41015Y485433D03*
X73550Y503589D03*
X76740Y498969D03*
X69815Y499033D03*
X69615Y493333D03*
X79160Y504249D03*
X58715Y590333D03*
X74724Y588857D03*
X57515Y708733D03*
X73715Y711333D03*
X97821Y397330D03*
X81535Y388844D03*
X110315Y406333D03*
X81415Y371233D03*
X80700Y377000D03*
X81946Y383090D03*
X98215Y425833D03*
X102388Y440622D03*
X117915Y427033D03*
X102508Y434585D03*
X106050Y477138D03*
X150029Y473321D03*
X85871Y485571D03*
X117815Y480433D03*
X95200Y474700D03*
X80416Y481610D03*
X134215Y475533D03*
X134163Y469043D03*
X141715Y467833D03*
X149563Y441783D03*
X141811Y433800D03*
X145782Y477006D03*
X146090Y457318D03*
X110050Y461812D03*
X81029Y495229D03*
X88215Y497733D03*
X84549Y502012D03*
X86015Y608633D03*
X84951Y579808D03*
X84752Y588361D03*
X95136Y592963D03*
X80915Y601033D03*
X87148Y596126D03*
X97296Y715873D03*
X83715Y700033D03*
X97047Y707261D03*
X107786Y704092D03*
X99706Y699717D03*
X86515Y707633D03*
X168824Y458743D03*
X153915Y465533D03*
X159663Y465693D03*
X173765Y461522D03*
X168118Y483682D03*
X187021Y462557D03*
X179407Y452283D03*
X182377Y474560D03*
X188616Y476694D03*
X194083Y469148D03*
X187689Y456913D03*
X183070Y466936D03*
X187600Y444200D03*
X184252Y439562D03*
X186200Y449700D03*
X172615Y442533D03*
X157500Y476921D03*
X193581Y457779D03*
X172415Y478733D03*
X165317Y465426D03*
X188457Y468481D03*
X166615Y442233D03*
X178300Y440135D03*
X169917Y489083D03*
X170474Y500652D03*
X164711Y495322D03*
X172992Y494239D03*
X709315Y443333D03*
G54D44*
X43500Y534600D03*
X118263Y409683D03*
X126310Y459803D03*
X102643Y459897D03*
X680800Y529200D03*
X701500D03*
G54D18*
X55700Y87600D03*
X59274Y87603D03*
X35230Y306738D03*
X134663Y456583D03*
X681300Y510400D03*
X648500Y536800D03*
X677800Y510400D03*
X725784Y554587D03*
G54D36*
X77963Y273483D03*
Y270923D03*
Y268363D03*
Y242773D03*
Y245333D03*
Y247888D03*
Y250448D03*
Y253008D03*
Y255568D03*
Y258128D03*
Y260683D03*
Y263243D03*
Y265803D03*
Y291393D03*
Y288833D03*
Y286278D03*
Y283718D03*
Y281158D03*
Y278598D03*
Y276038D03*
X161963Y242773D03*
Y245333D03*
Y247888D03*
Y250448D03*
Y253008D03*
Y255568D03*
Y258128D03*
Y260683D03*
Y263243D03*
Y265803D03*
Y273483D03*
Y270923D03*
Y268363D03*
Y291393D03*
Y288833D03*
Y286278D03*
Y283718D03*
Y281158D03*
Y278598D03*
Y276038D03*
G54D27*
X50244Y180974D03*
Y191974D03*
X44879Y511272D03*
Y522272D03*
G54D54*
X102363Y454883D03*
X125579Y427173D03*
X701500Y524200D03*
X680800D03*
G54D45*
X62977Y500748D03*
G54D63*
X694858Y466020D03*
G54D19*
X55700Y91200D03*
X59274Y91203D03*
X35230Y310338D03*
X134663Y460183D03*
X681300Y514000D03*
X648500Y540400D03*
X677800Y514000D03*
X725784Y558187D03*
G54D37*
X57900Y226200D03*
X182900Y308800D03*
G54D28*
X65830Y181464D03*
X58080D03*
X61955Y188964D03*
X56759Y199321D03*
X49009D03*
X52884Y206821D03*
G54D46*
X57377Y500748D03*
G54D55*
X144843Y812994D03*
Y860234D03*
X286982Y828335D03*
X276982D03*
X286982Y818335D03*
X276982D03*
X356982Y828335D03*
X346982D03*
X336982D03*
X326982D03*
X316982D03*
X306982D03*
X296982D03*
X356982Y818335D03*
X346982D03*
X336982D03*
X326982D03*
X316982D03*
X306982D03*
X296982D03*
X366982Y828335D03*
Y818335D03*
G54D64*
X779564Y330730D03*
Y740179D03*
G54D29*
X47940Y212898D03*
G54D56*
X172508Y238287D03*
X180108D03*
X680225Y486151D03*
X672625D03*
X679809Y478423D03*
X672209D03*
G54D47*
X60403Y524823D03*
Y517073D03*
X52903Y520948D03*
X57065Y544023D03*
Y536273D03*
X49565Y540148D03*
G54D38*
X53547Y322486D03*
Y302486D03*
X182681Y580832D03*
Y560832D03*
G54D65*
X781514Y334665D03*
Y338605D03*
Y342540D03*
Y346480D03*
Y350415D03*
Y354350D03*
Y358290D03*
Y362225D03*
Y366165D03*
Y370100D03*
Y381910D03*
Y385850D03*
Y389785D03*
Y393720D03*
Y397660D03*
Y401595D03*
Y405535D03*
Y409470D03*
Y413405D03*
Y417345D03*
Y421280D03*
Y425220D03*
Y429155D03*
Y433090D03*
Y437030D03*
Y440965D03*
Y444905D03*
Y448840D03*
Y452775D03*
Y456715D03*
Y460650D03*
Y464590D03*
Y468525D03*
Y472460D03*
Y476400D03*
Y480335D03*
Y484275D03*
Y488210D03*
Y492145D03*
Y496085D03*
Y500020D03*
Y503960D03*
Y507895D03*
Y511830D03*
Y515770D03*
Y519705D03*
Y523645D03*
Y527580D03*
Y531515D03*
Y535455D03*
Y539390D03*
Y543330D03*
Y547265D03*
Y551200D03*
Y555140D03*
Y559075D03*
Y563015D03*
Y566950D03*
Y570885D03*
Y574825D03*
Y578760D03*
Y582700D03*
Y586635D03*
Y590575D03*
Y594510D03*
Y598445D03*
Y602385D03*
Y606320D03*
Y610260D03*
Y614195D03*
Y618130D03*
Y622070D03*
Y626005D03*
Y629945D03*
Y633880D03*
Y637815D03*
Y641755D03*
Y645690D03*
Y649630D03*
Y653565D03*
Y657500D03*
Y744114D03*
Y748054D03*
Y751989D03*
Y755929D03*
Y759864D03*
Y763799D03*
Y767739D03*
Y771674D03*
Y775614D03*
Y779549D03*
Y791359D03*
Y795299D03*
Y799234D03*
Y803169D03*
Y807109D03*
Y811044D03*
Y814984D03*
G54D66*
G01X-771361Y-182763D02*
Y-262763D01*
G01Y-218263D02*
X373639D01*
G01X-771361Y-262763D02*
X373639D01*
G01X-775361Y-166763D02*
G02I-12000J0D01*
G01X-780511D02*
G02I-6850J0D01*
G01X-787361Y-182763D02*
Y-150763D01*
G01X-771361Y-166763D02*
X-803361D01*
G01X-771361Y-182763D02*
X373639D01*
G01X-413861D02*
Y-262763D01*
G01X-276361Y-182763D02*
Y-262763D01*
G01X-161361Y-182763D02*
Y-262763D01*
G01X6139Y-182763D02*
Y-262763D01*
G01X176139Y-182763D02*
Y-262763D01*
G01X373639Y-182763D02*
Y-262763D01*
G01X401639Y-166763D02*
G02I-12000J0D01*
G01X396489D02*
G02I-6850J0D01*
G01X389639Y-182763D02*
Y-150763D01*
G01X405639Y-166763D02*
X373639D01*
G54D57*
X419225Y453324D03*
G54D39*
X32984Y299567D03*
X30424D03*
X27864D03*
X25304D03*
Y283267D03*
X27864D03*
X30424D03*
X32984D03*
X687385Y518741D03*
X689945D03*
X692505D03*
X695065D03*
Y535041D03*
X692505D03*
X689945D03*
X687385D03*
X712102Y553333D03*
Y537033D03*
X654710Y540455D03*
X657270D03*
X659830D03*
X662390D03*
Y556755D03*
X659830D03*
X657270D03*
X654710D03*
X719782Y553333D03*
X717222D03*
X714662D03*
Y537033D03*
X717222D03*
X719782D03*
G54D48*
X54724Y557087D03*
Y620079D03*
Y675197D03*
Y738189D03*
X144843Y798779D03*
Y874449D03*
G54D67*
G01X-755164Y-252763D02*
Y-235263D01*
G01X-746868D02*
X-755164Y-246055D01*
G01X-745558Y-252763D02*
X-751453Y-241097D01*
G01X-737883Y-252763D02*
Y-235263D01*
X-727839Y-252763D01*
Y-235263D01*
G01X-715361Y-252763D02*
X-717108Y-252471D01*
X-718636Y-251305D01*
X-719946Y-249555D01*
X-720820Y-247513D01*
X-721256Y-245180D01*
Y-242846D01*
X-720820Y-240513D01*
X-719946Y-238471D01*
X-718636Y-236722D01*
X-717108Y-235555D01*
X-715361Y-235263D01*
X-713615Y-235555D01*
X-712086Y-236722D01*
X-710776Y-238471D01*
X-709902Y-240513D01*
X-709466Y-242846D01*
Y-245180D01*
X-709902Y-247513D01*
X-710776Y-249555D01*
X-712086Y-251305D01*
X-713615Y-252471D01*
X-715361Y-252763D01*
G01X-702446D02*
X-693276Y-235263D01*
G01X-702446D02*
X-693276Y-252763D01*
G01X-658494D02*
X-667228D01*
Y-235263D01*
X-658494D01*
G01X-661988Y-243721D02*
X-667228D01*
G01X-649946Y-252763D02*
X-640776Y-235263D01*
G01X-649946D02*
X-640776Y-252763D01*
G01X-632228D02*
Y-235263D01*
X-626988D01*
X-625241Y-236138D01*
X-623931Y-238180D01*
X-623494Y-240513D01*
X-623931Y-242846D01*
X-625023Y-244596D01*
X-626988Y-245472D01*
X-632228D01*
G01X-615820Y-252763D02*
X-610361Y-235263D01*
X-604902Y-252763D01*
G01X-606868Y-246638D02*
X-613855D01*
G01X-597883Y-252763D02*
Y-235263D01*
X-587839Y-252763D01*
Y-235263D01*
G01X-580164Y-252763D02*
Y-235263D01*
X-575798D01*
X-574051Y-236138D01*
X-572741Y-237305D01*
X-571649Y-239054D01*
X-570776Y-241097D01*
X-570558Y-244013D01*
X-570776Y-246930D01*
X-571649Y-248972D01*
X-572741Y-250722D01*
X-574051Y-251888D01*
X-575798Y-252763D01*
X-580164D01*
G01X-553494D02*
X-562228D01*
Y-235263D01*
X-553494D01*
G01X-556988Y-243721D02*
X-562228D01*
G01X-544728Y-252763D02*
Y-235263D01*
X-539269D01*
X-537523Y-236138D01*
X-536431Y-237305D01*
X-535994Y-239638D01*
X-536431Y-241972D01*
X-537741Y-243430D01*
X-539269Y-244305D01*
X-544728D01*
G01X-539269D02*
X-535994Y-252763D01*
G01X-503615Y-243430D02*
X-502741Y-242555D01*
X-502086Y-241097D01*
X-501649Y-239054D01*
X-502086Y-237305D01*
X-502959Y-236138D01*
X-504488Y-235263D01*
X-510383D01*
Y-252763D01*
X-503178D01*
X-501649Y-251597D01*
X-500776Y-249846D01*
X-500339Y-247805D01*
X-500776Y-245763D01*
X-502086Y-244013D01*
X-503615Y-243430D01*
X-510383D01*
G01X-487861Y-252763D02*
X-489608Y-252471D01*
X-491136Y-251305D01*
X-492446Y-249555D01*
X-493320Y-247513D01*
X-493756Y-245180D01*
Y-242846D01*
X-493320Y-240513D01*
X-492446Y-238471D01*
X-491136Y-236722D01*
X-489608Y-235555D01*
X-487861Y-235263D01*
X-486115Y-235555D01*
X-484586Y-236722D01*
X-483276Y-238471D01*
X-482402Y-240513D01*
X-481966Y-242846D01*
Y-245180D01*
X-482402Y-247513D01*
X-483276Y-249555D01*
X-484586Y-251305D01*
X-486115Y-252471D01*
X-487861Y-252763D01*
G01X-475820D02*
X-470361Y-235263D01*
X-464902Y-252763D01*
G01X-466868Y-246638D02*
X-473855D01*
G01X-457228Y-252763D02*
Y-235263D01*
X-451769D01*
X-450023Y-236138D01*
X-448931Y-237305D01*
X-448494Y-239638D01*
X-448931Y-241972D01*
X-450241Y-243430D01*
X-451769Y-244305D01*
X-457228D01*
G01X-451769D02*
X-448494Y-252763D01*
G01X-440164D02*
Y-235263D01*
X-435798D01*
X-434051Y-236138D01*
X-432741Y-237305D01*
X-431649Y-239054D01*
X-430776Y-241097D01*
X-430558Y-244013D01*
X-430776Y-246930D01*
X-431649Y-248972D01*
X-432741Y-250722D01*
X-434051Y-251888D01*
X-435798Y-252763D01*
X-440164D01*
G01X-633538Y-207763D02*
Y-190263D01*
X-627861Y-204846D01*
X-622184Y-190263D01*
Y-207763D01*
G01X-610361D02*
X-611671Y-207471D01*
X-612981Y-206305D01*
X-613855Y-204263D01*
X-614291Y-201930D01*
X-613855Y-199596D01*
X-612981Y-197555D01*
X-611671Y-196388D01*
X-610361Y-196097D01*
X-609051Y-196388D01*
X-607741Y-197555D01*
X-606868Y-199596D01*
X-606649Y-201930D01*
X-606868Y-204263D01*
X-607741Y-206305D01*
X-609051Y-207471D01*
X-610361Y-207763D01*
G01X-588931Y-190263D02*
Y-207763D01*
G01Y-205139D02*
X-589804Y-206597D01*
X-591115Y-207471D01*
X-592643Y-207763D01*
X-594389Y-207180D01*
X-595699Y-205722D01*
X-596573Y-203972D01*
X-596791Y-201930D01*
X-596573Y-199888D01*
X-595699Y-198138D01*
X-594389Y-196680D01*
X-592643Y-196097D01*
X-591115Y-196388D01*
X-590023Y-196972D01*
X-588931Y-198138D01*
G01X-578636Y-199888D02*
X-571649D01*
X-572304Y-197846D01*
X-573396Y-196680D01*
X-574924Y-196097D01*
X-576453Y-196388D01*
X-577763Y-197263D01*
X-578636Y-199305D01*
X-579073Y-201055D01*
Y-202805D01*
X-578636Y-204555D01*
X-577544Y-206305D01*
X-576234Y-207471D01*
X-574706Y-207763D01*
X-573178Y-207180D01*
X-571649Y-205430D01*
G01X-557861Y-207763D02*
Y-190263D01*
G01X-380161Y-252763D02*
Y-235263D01*
X-382781Y-238763D01*
G01Y-252763D02*
X-377541D01*
G01X-366809Y-238180D02*
X-365499Y-236430D01*
X-363971Y-235555D01*
X-362224Y-235263D01*
X-360041Y-235846D01*
X-358513Y-237305D01*
X-358076Y-239054D01*
X-358294Y-240805D01*
X-359168Y-242263D01*
X-363534Y-245180D01*
X-365499Y-247221D01*
X-366809Y-250139D01*
X-367246Y-252763D01*
X-358076D01*
G01X-345161Y-235263D02*
X-346908Y-235846D01*
X-348218Y-237305D01*
X-349091Y-239054D01*
X-349746Y-241388D01*
X-349964Y-244013D01*
X-349746Y-246638D01*
X-349091Y-248972D01*
X-348218Y-250722D01*
X-346908Y-252180D01*
X-345161Y-252763D01*
X-343415Y-252180D01*
X-342104Y-250722D01*
X-341231Y-248972D01*
X-340576Y-246638D01*
X-340358Y-244013D01*
X-340576Y-241388D01*
X-341231Y-239054D01*
X-342104Y-237305D01*
X-343415Y-235846D01*
X-345161Y-235263D01*
G01X-327661D02*
X-329408Y-235846D01*
X-330718Y-237305D01*
X-331591Y-239054D01*
X-332246Y-241388D01*
X-332464Y-244013D01*
X-332246Y-246638D01*
X-331591Y-248972D01*
X-330718Y-250722D01*
X-329408Y-252180D01*
X-327661Y-252763D01*
X-325915Y-252180D01*
X-324604Y-250722D01*
X-323731Y-248972D01*
X-323076Y-246638D01*
X-322858Y-244013D01*
X-323076Y-241388D01*
X-323731Y-239054D01*
X-324604Y-237305D01*
X-325915Y-235846D01*
X-327661Y-235263D01*
G01X-307541Y-252763D02*
Y-235263D01*
X-315620Y-247805D01*
X-304702D01*
G01X-393278Y-207763D02*
Y-190263D01*
X-388038D01*
X-386291Y-191138D01*
X-384981Y-193180D01*
X-384544Y-195513D01*
X-384981Y-197846D01*
X-386073Y-199596D01*
X-388038Y-200472D01*
X-393278D01*
G01X-366608Y-191722D02*
X-367918Y-190846D01*
X-369446Y-190263D01*
X-371193D01*
X-373158Y-191138D01*
X-374686Y-192596D01*
X-375778Y-194347D01*
X-376651Y-197263D01*
X-376870Y-199888D01*
X-376433Y-202513D01*
X-375778Y-204263D01*
X-374468Y-206013D01*
X-372939Y-207180D01*
X-371411Y-207763D01*
X-369883D01*
X-368354Y-207180D01*
X-367044Y-206305D01*
X-365952Y-205139D01*
G01X-352165Y-198430D02*
X-351291Y-197555D01*
X-350636Y-196097D01*
X-350199Y-194054D01*
X-350636Y-192305D01*
X-351509Y-191138D01*
X-353038Y-190263D01*
X-358933D01*
Y-207763D01*
X-351728D01*
X-350199Y-206597D01*
X-349326Y-204846D01*
X-348889Y-202805D01*
X-349326Y-200763D01*
X-350636Y-199013D01*
X-352165Y-198430D01*
X-358933D01*
G01X-342961Y-213596D02*
X-329861D01*
G01X-323933Y-207763D02*
Y-190263D01*
X-313889Y-207763D01*
Y-190263D01*
G01X-301411Y-207763D02*
X-303158Y-207471D01*
X-304686Y-206305D01*
X-305996Y-204555D01*
X-306870Y-202513D01*
X-307306Y-200180D01*
Y-197846D01*
X-306870Y-195513D01*
X-305996Y-193471D01*
X-304686Y-191722D01*
X-303158Y-190555D01*
X-301411Y-190263D01*
X-299665Y-190555D01*
X-298136Y-191722D01*
X-296826Y-193471D01*
X-295952Y-195513D01*
X-295516Y-197846D01*
Y-200180D01*
X-295952Y-202513D01*
X-296826Y-204555D01*
X-298136Y-206305D01*
X-299665Y-207471D01*
X-301411Y-207763D01*
G01X-218861Y-252763D02*
Y-235263D01*
X-221481Y-238763D01*
G01Y-252763D02*
X-216241D01*
G01X-250570Y-190263D02*
X-245111Y-207763D01*
X-239652Y-190263D01*
G01X-223244Y-207763D02*
X-231978D01*
Y-190263D01*
X-223244D01*
G01X-226738Y-198721D02*
X-231978D01*
G01X-214478Y-207763D02*
Y-190263D01*
X-209019D01*
X-207273Y-191138D01*
X-206181Y-192305D01*
X-205744Y-194638D01*
X-206181Y-196972D01*
X-207491Y-198430D01*
X-209019Y-199305D01*
X-214478D01*
G01X-209019D02*
X-205744Y-207763D01*
G01X-192611Y-208346D02*
X-193048Y-208055D01*
Y-207471D01*
X-192611Y-207180D01*
X-192174Y-207471D01*
Y-208055D01*
X-192611Y-208346D01*
G01X-44407Y-243430D02*
X-45281Y-242555D01*
X-45936Y-241097D01*
X-46373Y-239054D01*
X-45936Y-237305D01*
X-45063Y-236138D01*
X-43534Y-235263D01*
X-37639D01*
Y-252763D01*
X-44844D01*
X-46373Y-251597D01*
X-47246Y-249846D01*
X-47683Y-247805D01*
X-47246Y-245763D01*
X-45936Y-244013D01*
X-44407Y-243430D01*
X-37639D01*
G01X-54484Y-252763D02*
Y-235263D01*
X-60161Y-249846D01*
X-65838Y-235263D01*
Y-252763D01*
G01X-72202D02*
X-77661Y-235263D01*
X-83120Y-252763D01*
G01X-81154Y-246638D02*
X-74167D01*
G01X-90576Y-250430D02*
X-92323Y-251888D01*
X-94288Y-252763D01*
X-96034D01*
X-97781Y-251888D01*
X-99091Y-250430D01*
X-99746Y-248388D01*
X-99309Y-246347D01*
X-98218Y-244596D01*
X-96253Y-243430D01*
X-93633Y-242846D01*
X-92104Y-241680D01*
X-91449Y-239638D01*
X-91886Y-237596D01*
X-92978Y-236138D01*
X-94506Y-235263D01*
X-96034D01*
X-97563Y-235846D01*
X-98873Y-237305D01*
G01X-107858Y-252763D02*
Y-235263D01*
G01X-116154D02*
X-107858Y-246055D01*
G01X-117464Y-252763D02*
X-111569Y-241097D01*
G01X-125778Y-190263D02*
Y-207763D01*
X-117044D01*
G01X-99981D02*
Y-196097D01*
G01Y-198138D02*
X-100854Y-196972D01*
X-102165Y-196388D01*
X-103693Y-196097D01*
X-105221Y-196680D01*
X-106531Y-197846D01*
X-107405Y-199596D01*
X-107841Y-201930D01*
X-107405Y-204263D01*
X-106531Y-206013D01*
X-105221Y-207180D01*
X-103693Y-207763D01*
X-102165Y-207471D01*
X-100854Y-206597D01*
X-99981Y-205430D01*
G01X-90996Y-213013D02*
X-89686Y-213596D01*
X-87939Y-213013D01*
X-86848Y-211847D01*
X-85974Y-210388D01*
X-84665Y-205722D01*
X-81826Y-196097D01*
G01X-88813D02*
X-84665Y-205722D01*
G01X-72186Y-199888D02*
X-65199D01*
X-65854Y-197846D01*
X-66946Y-196680D01*
X-68474Y-196097D01*
X-70003Y-196388D01*
X-71313Y-197263D01*
X-72186Y-199305D01*
X-72623Y-201055D01*
Y-202805D01*
X-72186Y-204555D01*
X-71094Y-206305D01*
X-69784Y-207471D01*
X-68256Y-207763D01*
X-66728Y-207180D01*
X-65199Y-205430D01*
G01X-54468Y-207763D02*
Y-196097D01*
G01Y-198430D02*
X-53376Y-197263D01*
X-52284Y-196388D01*
X-50756Y-196097D01*
X-49665Y-196388D01*
X-48354Y-197263D01*
G01X-37186Y-205722D02*
X-36094Y-206888D01*
X-34566Y-207763D01*
X-33256D01*
X-31946Y-207180D01*
X-31073Y-206305D01*
X-30636Y-205139D01*
X-30854Y-203388D01*
X-31728Y-202513D01*
X-35658Y-200763D01*
X-36531Y-198721D01*
X-36094Y-197263D01*
X-35221Y-196388D01*
X-33911Y-196097D01*
X-32601Y-196388D01*
X-31291Y-197263D01*
G01X51772Y-235263D02*
Y-252763D01*
X60506D01*
G01X68836Y-235263D02*
Y-247805D01*
X69709Y-250430D01*
X71456Y-252180D01*
X73639Y-252763D01*
X75822Y-252180D01*
X77569Y-250430D01*
X78442Y-247805D01*
Y-235263D01*
G01X95942Y-236722D02*
X94632Y-235846D01*
X93104Y-235263D01*
X91357D01*
X89392Y-236138D01*
X87864Y-237596D01*
X86772Y-239347D01*
X85899Y-242263D01*
X85680Y-244888D01*
X86117Y-247513D01*
X86772Y-249263D01*
X88082Y-251013D01*
X89611Y-252180D01*
X91139Y-252763D01*
X92667D01*
X94196Y-252180D01*
X95506Y-251305D01*
X96598Y-250139D01*
G01X103836Y-252763D02*
Y-235263D01*
G01X112132D02*
X103836Y-246055D01*
G01X113442Y-252763D02*
X107547Y-241097D01*
G01X126139Y-252763D02*
Y-244888D01*
X121772Y-235263D01*
G01X130506D02*
X126139Y-244888D01*
G01X25086Y-207763D02*
Y-190263D01*
X29452D01*
X31199Y-191138D01*
X32509Y-192305D01*
X33601Y-194054D01*
X34474Y-196097D01*
X34692Y-199013D01*
X34474Y-201930D01*
X33601Y-203972D01*
X32509Y-205722D01*
X31199Y-206888D01*
X29452Y-207763D01*
X25086D01*
G01X44114Y-199888D02*
X51101D01*
X50446Y-197846D01*
X49354Y-196680D01*
X47826Y-196097D01*
X46297Y-196388D01*
X44987Y-197263D01*
X44114Y-199305D01*
X43677Y-201055D01*
Y-202805D01*
X44114Y-204555D01*
X45206Y-206305D01*
X46516Y-207471D01*
X48044Y-207763D01*
X49572Y-207180D01*
X51101Y-205430D01*
G01X61614Y-205722D02*
X62706Y-206888D01*
X64234Y-207763D01*
X65544D01*
X66854Y-207180D01*
X67727Y-206305D01*
X68164Y-205139D01*
X67946Y-203388D01*
X67072Y-202513D01*
X63142Y-200763D01*
X62269Y-198721D01*
X62706Y-197263D01*
X63579Y-196388D01*
X64889Y-196097D01*
X66199Y-196388D01*
X67509Y-197263D01*
G01X82389Y-196097D02*
Y-207763D01*
G01Y-191430D02*
X81952Y-191138D01*
Y-190555D01*
X82389Y-190263D01*
X82826Y-190555D01*
Y-191138D01*
X82389Y-191430D01*
G01X96832Y-212138D02*
X98361Y-213305D01*
X100107Y-213596D01*
X101635Y-213305D01*
X102946Y-211847D01*
X103819Y-209805D01*
Y-196097D01*
G01Y-198430D02*
X102946Y-197263D01*
X101635Y-196388D01*
X100107Y-196097D01*
X98361Y-196680D01*
X97269Y-197846D01*
X96395Y-199888D01*
X95959Y-201930D01*
X96177Y-203680D01*
X97051Y-205722D01*
X98361Y-207180D01*
X100107Y-207763D01*
X101417Y-207471D01*
X102946Y-206305D01*
X103819Y-205139D01*
G01X113677Y-207763D02*
Y-196097D01*
G01Y-199013D02*
X114551Y-197555D01*
X115861Y-196388D01*
X117607Y-196097D01*
X119135Y-196388D01*
X120446Y-197555D01*
X121101Y-199596D01*
Y-207763D01*
G01X131614Y-199888D02*
X138601D01*
X137946Y-197846D01*
X136854Y-196680D01*
X135326Y-196097D01*
X133797Y-196388D01*
X132487Y-197263D01*
X131614Y-199305D01*
X131177Y-201055D01*
Y-202805D01*
X131614Y-204555D01*
X132706Y-206305D01*
X134016Y-207471D01*
X135544Y-207763D01*
X137072Y-207180D01*
X138601Y-205430D01*
G01X149332Y-207763D02*
Y-196097D01*
G01Y-198430D02*
X150424Y-197263D01*
X151516Y-196388D01*
X153044Y-196097D01*
X154135Y-196388D01*
X155446Y-197263D01*
G01X196089Y-252763D02*
Y-235263D01*
X193469Y-238763D01*
G01Y-252763D02*
X198709D01*
G01X213589Y-235263D02*
X211842Y-235846D01*
X210532Y-237305D01*
X209659Y-239054D01*
X209004Y-241388D01*
X208786Y-244013D01*
X209004Y-246638D01*
X209659Y-248972D01*
X210532Y-250722D01*
X211842Y-252180D01*
X213589Y-252763D01*
X215335Y-252180D01*
X216646Y-250722D01*
X217519Y-248972D01*
X218174Y-246638D01*
X218392Y-244013D01*
X218174Y-241388D01*
X217519Y-239054D01*
X216646Y-237305D01*
X215335Y-235846D01*
X213589Y-235263D01*
G01X227159Y-253346D02*
X235019Y-235263D01*
G01X248589Y-252763D02*
Y-235263D01*
X245969Y-238763D01*
G01Y-252763D02*
X251209D01*
G01X261941Y-245472D02*
X263469Y-243430D01*
X264779Y-242263D01*
X266526Y-241680D01*
X268054Y-242263D01*
X269146Y-243430D01*
X270019Y-245180D01*
X270237Y-247221D01*
X270019Y-248972D01*
X269146Y-250722D01*
X267835Y-252180D01*
X266307Y-252763D01*
X264561Y-252180D01*
X263032Y-250430D01*
X262159Y-247805D01*
X261941Y-244888D01*
X262377Y-241097D01*
X263032Y-239054D01*
X264124Y-237013D01*
X265652Y-235555D01*
X267181Y-235263D01*
X268709Y-235846D01*
X269801Y-237305D01*
G01X279659Y-253346D02*
X287519Y-235263D01*
G01X296941Y-238180D02*
X298251Y-236430D01*
X299779Y-235555D01*
X301526Y-235263D01*
X303709Y-235846D01*
X305237Y-237305D01*
X305674Y-239054D01*
X305456Y-240805D01*
X304582Y-242263D01*
X300216Y-245180D01*
X298251Y-247221D01*
X296941Y-250139D01*
X296504Y-252763D01*
X305674D01*
G01X318589Y-235263D02*
X316842Y-235846D01*
X315532Y-237305D01*
X314659Y-239054D01*
X314004Y-241388D01*
X313786Y-244013D01*
X314004Y-246638D01*
X314659Y-248972D01*
X315532Y-250722D01*
X316842Y-252180D01*
X318589Y-252763D01*
X320335Y-252180D01*
X321646Y-250722D01*
X322519Y-248972D01*
X323174Y-246638D01*
X323392Y-244013D01*
X323174Y-241388D01*
X322519Y-239054D01*
X321646Y-237305D01*
X320335Y-235846D01*
X318589Y-235263D01*
G01X336089Y-252763D02*
Y-235263D01*
X333469Y-238763D01*
G01Y-252763D02*
X338709D01*
G01X349441Y-238180D02*
X350751Y-236430D01*
X352279Y-235555D01*
X354026Y-235263D01*
X356209Y-235846D01*
X357737Y-237305D01*
X358174Y-239054D01*
X357956Y-240805D01*
X357082Y-242263D01*
X352716Y-245180D01*
X350751Y-247221D01*
X349441Y-250139D01*
X349004Y-252763D01*
X358174D01*
G01X243786Y-207763D02*
Y-190263D01*
X248152D01*
X249899Y-191138D01*
X251209Y-192305D01*
X252301Y-194054D01*
X253174Y-196097D01*
X253392Y-199013D01*
X253174Y-201930D01*
X252301Y-203972D01*
X251209Y-205722D01*
X249899Y-206888D01*
X248152Y-207763D01*
X243786D01*
G01X270019D02*
Y-196097D01*
G01Y-198138D02*
X269146Y-196972D01*
X267835Y-196388D01*
X266307Y-196097D01*
X264779Y-196680D01*
X263469Y-197846D01*
X262595Y-199596D01*
X262159Y-201930D01*
X262595Y-204263D01*
X263469Y-206013D01*
X264779Y-207180D01*
X266307Y-207763D01*
X267835Y-207471D01*
X269146Y-206597D01*
X270019Y-205430D01*
G01X283589Y-190263D02*
Y-207763D01*
G01X280532Y-196097D02*
X286646D01*
G01X297814Y-199888D02*
X304801D01*
X304146Y-197846D01*
X303054Y-196680D01*
X301526Y-196097D01*
X299997Y-196388D01*
X298687Y-197263D01*
X297814Y-199305D01*
X297377Y-201055D01*
Y-202805D01*
X297814Y-204555D01*
X298906Y-206305D01*
X300216Y-207471D01*
X301744Y-207763D01*
X303272Y-207180D01*
X304801Y-205430D01*
G54D58*
X414107Y443581D03*
X416666D03*
X419225D03*
X421784D03*
X424343D03*
Y463067D03*
X421784D03*
X419225D03*
X416666D03*
X414107D03*
G54D49*
X62000Y609872D03*
Y605972D03*
X62100Y600272D03*
Y596372D03*
Y576887D03*
Y572987D03*
X62200Y567387D03*
Y563487D03*
X62651Y694403D03*
Y690503D03*
Y684703D03*
Y680803D03*
X61600Y728513D03*
Y724613D03*
X61700Y718613D03*
Y714713D03*
X131100Y228600D03*
X90763Y228783D03*
X90819Y305456D03*
X121263Y305503D03*
X131963Y305603D03*
X106805Y413570D03*
X114863Y421283D03*
X120963Y441583D03*
X121763Y449983D03*
X113363Y441583D03*
X109463Y434383D03*
X136163Y441583D03*
X129663Y449183D03*
X119263Y433683D03*
X126983Y434871D03*
Y431371D03*
X129663Y452683D03*
X171696Y269694D03*
X168269Y432425D03*
X157063Y440683D03*
X150640Y837095D03*
X150751Y832781D03*
Y828981D03*
X152236Y817740D03*
Y814140D03*
X151488Y853750D03*
X151561Y850210D03*
X150440Y840895D03*
X707930Y464221D03*
X708009Y453723D03*
X653700Y533400D03*
G54D59*
X428968Y448206D03*
Y450765D03*
Y453324D03*
Y455883D03*
Y458442D03*
X409482D03*
Y455883D03*
Y453324D03*
Y450765D03*
Y448206D03*
M02*
